# SCM (Grand Teton) — schematic netlist excerpt (pin names and nets, part order shuffled) for the footprints in the layout excerpt that follows; sources: Cadence DE-HDL packaged netlist, KiCad conversion of 12092022_DA0F0TMDCD0_F0T_Management_Board_D_brd_V3_OCP.brd

U38  PRTR5V0U2X  IC  pkg SOT143XB  page 29
  GND  = GND
  IO1  = USB2_01_F_DP
  IO2  = USB2_01_F_DN
  VCC  = P5V_USB_REAR

R266  Q_RES  4.7K 1% EMPTY  pkg 0402LF  page 27 : A = P3V3_AUX ; B = FM_ME_BT_DONE

(kicad_pcb
	(version 20260206)
	(generator "pcbnew")
	(generator_version "10.0")
	(general
		(thickness 1.6)
		(legacy_teardrops no)
	)
	(paper "A4")
	(title_block
		(title "12092022_DA0F0TMDCD0_F0T_Management_Board_D_brd_V3_OCP.brd")
		(comment 1 "Grand Teton / footprints 284-285 of 1440")
	)
	(layers
		(0 "F.Cu" signal "TOP")
		(4 "In1.Cu" signal "GND")
		(6 "In2.Cu" signal "IN1")
		(8 "In3.Cu" signal "GND1")
		(10 "In4.Cu" signal "IN2")
		(12 "In5.Cu" signal "VCC")
		(14 "In6.Cu" signal "VCC1")
		(16 "In7.Cu" signal "IN3")
		(18 "In8.Cu" signal "GND2")
		(20 "In9.Cu" signal "IN4")
		(22 "In10.Cu" signal "GND3")
		(2 "B.Cu" signal "BOTTOM")
		(9 "F.Adhes" user "F.Adhesive")
		(11 "B.Adhes" user "B.Adhesive")
		(13 "F.Paste" user "Package Geometry/Pastemask Top")
		(15 "B.Paste" user "Package Geometry/Pastemask Bottom")
		(5 "F.SilkS" user "Ref Des/Silkscreen Top")
		(7 "B.SilkS" user "Ref Des/Silkscreen Bottom")
		(1 "F.Mask" user "Board Geometry/Soldermask Top")
		(3 "B.Mask" user "Board Geometry/Soldermask Bottom")
		(17 "Dwgs.User" user "User.Drawings")
		(19 "Cmts.User" user "User.Comments")
		(21 "Eco1.User" user "User.Eco1")
		(23 "Eco2.User" user "User.Eco2")
		(25 "Edge.Cuts" user "Board Geometry/Outline")
		(27 "Margin" user)
		(31 "F.CrtYd" user "Package Geometry/Place Bound Top")
		(29 "B.CrtYd" user "Package Geometry/Place Bound Bottom")
		(35 "F.Fab" user "Ref Des/Assembly Top")
		(33 "B.Fab" user "Ref Des/Assembly Bottom")
	)
	(footprint ""
		(layer "F.Cu")
		(at 39.9288 -43.434)
		(property "Reference" "R266"
			(at 0 0 0)
			(layer "F.SilkS")
			(hide yes)
			(effects
				(font
					(size 1.27 1.27)
				)
			)
		)
		(property "Value" ""
			(at 0 0 0)
			(layer "F.Fab")
			(effects
				(font
					(size 1.27 1.27)
				)
			)
		)
		(duplicate_pad_numbers_are_jumpers no)
		(fp_line
			(start -0.7874 -0.4064)
			(end 0.7874 -0.4064)
			(stroke
				(width 0.1524)
				(type default)
			)
			(layer "F.SilkS")
		)
		(fp_line
			(start -0.7874 0.4064)
			(end -0.7874 -0.4064)
			(stroke
				(width 0.1524)
				(type default)
			)
			(layer "F.SilkS")
		)
		(fp_line
			(start 0.7874 -0.4064)
			(end 0.7874 0.4064)
			(stroke
				(width 0.1524)
				(type default)
			)
			(layer "F.SilkS")
		)
		(fp_line
			(start 0.7874 0.4064)
			(end -0.7874 0.4064)
			(stroke
				(width 0.1524)
				(type default)
			)
			(layer "F.SilkS")
		)
		(fp_line
			(start -0.67945 -0.305054)
			(end -0.12065 -0.305054)
			(stroke
				(width 0.1)
				(type default)
			)
			(layer "F.Fab")
		)
		(fp_line
			(start -0.67945 0.3048)
			(end -0.67945 -0.305054)
			(stroke
				(width 0.1)
				(type default)
			)
			(layer "F.Fab")
		)
		(fp_line
			(start -0.12065 -0.305054)
			(end -0.12065 -0.2794)
			(stroke
				(width 0.1)
				(type default)
			)
			(layer "F.Fab")
		)
		(fp_line
			(start -0.12065 -0.2794)
			(end 0.12065 -0.2794)
			(stroke
				(width 0.1)
				(type default)
			)
			(layer "F.Fab")
		)
		(fp_line
			(start -0.12065 0.2794)
			(end -0.12065 0.3048)
			(stroke
				(width 0.1)
				(type default)
			)
			(layer "F.Fab")
		)
		(fp_line
			(start -0.12065 0.3048)
			(end -0.67945 0.3048)
			(stroke
				(width 0.1)
				(type default)
			)
			(layer "F.Fab")
		)
		(fp_line
			(start 0.120396 0.2794)
			(end -0.12065 0.2794)
			(stroke
				(width 0.1)
				(type default)
			)
			(layer "F.Fab")
		)
		(fp_line
			(start 0.120396 0.3048)
			(end 0.120396 0.2794)
			(stroke
				(width 0.1)
				(type default)
			)
			(layer "F.Fab")
		)
		(fp_line
			(start 0.12065 -0.3048)
			(end 0.67945 -0.3048)
			(stroke
				(width 0.1)
				(type default)
			)
			(layer "F.Fab")
		)
		(fp_line
			(start 0.12065 -0.2794)
			(end 0.12065 -0.3048)
			(stroke
				(width 0.1)
				(type default)
			)
			(layer "F.Fab")
		)
		(fp_line
			(start 0.67945 -0.3048)
			(end 0.67945 0.3048)
			(stroke
				(width 0.1)
				(type default)
			)
			(layer "F.Fab")
		)
		(fp_line
			(start 0.67945 0.3048)
			(end 0.120396 0.3048)
			(stroke
				(width 0.1)
				(type default)
			)
			(layer "F.Fab")
		)
		(pad "1" smd circle
			(at -0.40005 0)
			(size 0 0)
			(layers "F.Cu" "F.Mask" "F.Paste")
			(net "P3V3_AUX")
		)
		(pad "2" smd circle
			(at 0.40005 0)
			(size 0 0)
			(layers "F.Cu" "F.Mask" "F.Paste")
			(net "FM_ME_BT_DONE")
		)
	)
	(footprint ""
		(layer "F.Cu")
		(at 31.70809 -16.503396 90)
		(property "Reference" "U38"
			(at -2.052066 1.69291 0)
			(unlocked yes)
			(layer "F.SilkS")
			(effects
				(font
					(size 0.7874 0.5842)
					(thickness 0.1524)
				)
				(justify left)
			)
		)
		(property "Value" ""
			(at 0 0 90)
			(layer "F.Fab")
			(effects
				(font
					(size 1.27 1.27)
				)
			)
		)
		(duplicate_pad_numbers_are_jumpers no)
		(fp_line
			(start 0.517398 -1.500124)
			(end 0.517398 0.122936)
			(stroke
				(width 0.1524)
				(type default)
			)
			(layer "F.SilkS")
		)
		(fp_line
			(start 0.374904 -1.500124)
			(end 0.517398 -1.500124)
			(stroke
				(width 0.1524)
				(type default)
			)
			(layer "F.SilkS")
		)
		(fp_line
			(start -0.517398 -1.500124)
			(end -0.336296 -1.500124)
			(stroke
				(width 0.1524)
				(type default)
			)
			(layer "F.SilkS")
		)
		(fp_line
			(start -0.517398 0.128016)
			(end -0.517398 -1.500124)
			(stroke
				(width 0.1524)
				(type default)
			)
			(layer "F.SilkS")
		)
		(fp_poly
			(pts
				(xy -1.5875 -0.621284) (xy -2.2225 -0.938784) (xy -2.2225 -0.303784)
			)
			(stroke
				(width 0)
				(type default)
			)
			(fill yes)
			(layer "F.SilkS")
		)
		(fp_line
			(start 0.700024 -1.500124)
			(end 0.700024 1.500124)
			(stroke
				(width 0.1)
				(type default)
			)
			(layer "F.Fab")
		)
		(fp_line
			(start -0.700024 -1.500124)
			(end 0.700024 -1.500124)
			(stroke
				(width 0.1)
				(type default)
			)
			(layer "F.Fab")
		)
		(fp_line
			(start 0.700024 1.500124)
			(end -0.700024 1.500124)
			(stroke
				(width 0.1)
				(type default)
			)
			(layer "F.Fab")
		)
		(fp_line
			(start -0.700024 1.500124)
			(end -0.700024 -1.500124)
			(stroke
				(width 0.1)
				(type default)
			)
			(layer "F.Fab")
		)
		(fp_poly
			(pts
				(xy -1.5113 -0.750062) (xy -2.1463 -1.067562) (xy -2.1463 -0.432562)
			)
			(stroke
				(width 0)
				(type default)
			)
			(fill yes)
			(layer "F.Fab")
		)
		(pad "1" smd rect
			(at -0.999998 -0.750062 90)
			(size 0.7112 1.016)
			(layers "F.Cu" "F.Mask" "F.Paste")
			(net "GND")
		)
		(pad "2" smd rect
			(at -0.999998 0.94996)
			(size 0.6096 0.7112)
			(layers "F.Cu" "F.Mask" "F.Paste")
			(net "USB2_01_F_DP")
		)
		(pad "3" smd rect
			(at 0.999998 0.94996)
			(size 0.6096 0.7112)
			(layers "F.Cu" "F.Mask" "F.Paste")
			(net "USB2_01_F_DN")
		)
		(pad "4" smd rect
			(at 0.999998 -0.94996)
			(size 0.6096 0.7112)
			(layers "F.Cu" "F.Mask" "F.Paste")
			(net "P5V_USB_REAR")
		)
	)
)
